# S9S_MB_2U (Grand Teton) — schematic netlist excerpt (pin names and nets, part order shuffled) for the footprints in the layout excerpt that follows; sources: Cadence DE-HDL packaged netlist, KiCad conversion of 03242023_DA0F0TMBIJ0_F0T_Motherboard_J_brd_V01_OCP.brd

R4448  Q_RES  10K 1% EMPTY  pkg 0402LF  page 196 : A = P3V3_AUX ; B = USB_HUB_2_PSELF

(kicad_pcb
	(version 20260206)
	(generator "pcbnew")
	(generator_version "10.0")
	(general
		(thickness 1.6)
		(legacy_teardrops no)
	)
	(paper "A4")
	(title_block
		(title "03242023_DA0F0TMBIJ0_F0T_Motherboard_J_brd_V01_OCP.brd")
		(comment 1 "Grand Teton / footprints 2193-2193 of 6105")
	)
	(layers
		(0 "F.Cu" signal "TOP")
		(4 "In1.Cu" signal "GND")
		(6 "In2.Cu" signal "IN1")
		(8 "In3.Cu" signal "GND1")
		(10 "In4.Cu" signal "IN2")
		(12 "In5.Cu" signal "GND2")
		(14 "In6.Cu" signal "IN3")
		(16 "In7.Cu" signal "GND3")
		(18 "In8.Cu" signal "VCC")
		(20 "In9.Cu" signal "VCC1")
		(22 "In10.Cu" signal "GND4")
		(24 "In11.Cu" signal "IN4")
		(26 "In12.Cu" signal "GND5")
		(28 "In13.Cu" signal "IN5")
		(30 "In14.Cu" signal "GND6")
		(32 "In15.Cu" signal "IN6")
		(34 "In16.Cu" signal "GND7")
		(2 "B.Cu" signal "BOTTOM")
		(9 "F.Adhes" user "F.Adhesive")
		(11 "B.Adhes" user "B.Adhesive")
		(13 "F.Paste" user "Package Geometry/Pastemask Top")
		(15 "B.Paste" user "Package Geometry/Pastemask Bottom")
		(5 "F.SilkS" user "Ref Des/Silkscreen Top")
		(7 "B.SilkS" user "Ref Des/Silkscreen Bottom")
		(1 "F.Mask" user "Board Geometry/Soldermask Top")
		(3 "B.Mask" user "Board Geometry/Soldermask Bottom")
		(17 "Dwgs.User" user "User.Drawings")
		(19 "Cmts.User" user "User.Comments")
		(21 "Eco1.User" user "User.Eco1")
		(23 "Eco2.User" user "User.Eco2")
		(25 "Edge.Cuts" user "Board Geometry/Outline")
		(27 "Margin" user)
		(31 "F.CrtYd" user "Package Geometry/Place Bound Top")
		(29 "B.CrtYd" user "Package Geometry/Place Bound Bottom")
		(35 "F.Fab" user "Ref Des/Assembly Top")
		(33 "B.Fab" user "Ref Des/Assembly Bottom")
	)
	(footprint ""
		(layer "F.Cu")
		(at 164.247576 -35.737546 180)
		(property "Reference" "R4448"
			(at 0 0 180)
			(layer "F.SilkS")
			(hide yes)
			(effects
				(font
					(size 1.27 1.27)
				)
			)
		)
		(property "Value" ""
			(at 0 0 180)
			(layer "F.Fab")
			(effects
				(font
					(size 1.27 1.27)
				)
			)
		)
		(duplicate_pad_numbers_are_jumpers no)
		(fp_line
			(start 0.7874 0.4064)
			(end -0.7874 0.4064)
			(stroke
				(width 0.1524)
				(type default)
			)
			(layer "F.SilkS")
		)
		(fp_line
			(start 0.7874 -0.4064)
			(end 0.7874 0.4064)
			(stroke
				(width 0.1524)
				(type default)
			)
			(layer "F.SilkS")
		)
		(fp_line
			(start -0.7874 0.4064)
			(end -0.7874 -0.4064)
			(stroke
				(width 0.1524)
				(type default)
			)
			(layer "F.SilkS")
		)
		(fp_line
			(start -0.7874 -0.4064)
			(end 0.7874 -0.4064)
			(stroke
				(width 0.1524)
				(type default)
			)
			(layer "F.SilkS")
		)
		(fp_line
			(start 0.67945 0.3048)
			(end 0.120396 0.3048)
			(stroke
				(width 0.1)
				(type default)
			)
			(layer "F.Fab")
		)
		(fp_line
			(start 0.67945 -0.3048)
			(end 0.67945 0.3048)
			(stroke
				(width 0.1)
				(type default)
			)
			(layer "F.Fab")
		)
		(fp_line
			(start 0.12065 -0.2794)
			(end 0.12065 -0.3048)
			(stroke
				(width 0.1)
				(type default)
			)
			(layer "F.Fab")
		)
		(fp_line
			(start 0.12065 -0.3048)
			(end 0.67945 -0.3048)
			(stroke
				(width 0.1)
				(type default)
			)
			(layer "F.Fab")
		)
		(fp_line
			(start 0.120396 0.3048)
			(end 0.120396 0.2794)
			(stroke
				(width 0.1)
				(type default)
			)
			(layer "F.Fab")
		)
		(fp_line
			(start 0.120396 0.2794)
			(end -0.12065 0.2794)
			(stroke
				(width 0.1)
				(type default)
			)
			(layer "F.Fab")
		)
		(fp_line
			(start -0.12065 0.3048)
			(end -0.67945 0.3048)
			(stroke
				(width 0.1)
				(type default)
			)
			(layer "F.Fab")
		)
		(fp_line
			(start -0.12065 0.2794)
			(end -0.12065 0.3048)
			(stroke
				(width 0.1)
				(type default)
			)
			(layer "F.Fab")
		)
		(fp_line
			(start -0.12065 -0.2794)
			(end 0.12065 -0.2794)
			(stroke
				(width 0.1)
				(type default)
			)
			(layer "F.Fab")
		)
		(fp_line
			(start -0.12065 -0.305054)
			(end -0.12065 -0.2794)
			(stroke
				(width 0.1)
				(type default)
			)
			(layer "F.Fab")
		)
		(fp_line
			(start -0.67945 0.3048)
			(end -0.67945 -0.305054)
			(stroke
				(width 0.1)
				(type default)
			)
			(layer "F.Fab")
		)
		(fp_line
			(start -0.67945 -0.305054)
			(end -0.12065 -0.305054)
			(stroke
				(width 0.1)
				(type default)
			)
			(layer "F.Fab")
		)
		(pad "1" smd circle
			(at -0.40005 0 180)
			(size 0 0)
			(layers "F.Cu" "F.Mask" "F.Paste")
			(net "P3V3_AUX")
		)
		(pad "2" smd circle
			(at 0.40005 0 180)
			(size 0 0)
			(layers "F.Cu" "F.Mask" "F.Paste")
			(net "USB_HUB_2_PSELF")
		)
	)
)
